(kicad_sch (version 20230121) (generator eeschema)

  (paper "A3")

  (title_block
    (title "HDMI-MIPI Bridge")
    (date "2023-07-20")
    (rev "1.3.1")
  )

  (junction (at 208.28 205.74) (diameter 0) (color 0 0 0 0)
  )
  (junction (at 208.28 228.6) (diameter 0) (color 0 0 0 0)
  )
  (junction (at 209.55 106.68) (diameter 0) (color 0 0 0 0)
  )
  (junction (at 208.28 198.12) (diameter 0) (color 0 0 0 0)
  )
  (junction (at 186.69 106.68) (diameter 0) (color 0 0 0 0)
  )
  (junction (at 186.69 101.6) (diameter 0) (color 0 0 0 0)
  )
  (junction (at 208.28 231.14) (diameter 0) (color 0 0 0 0)
  )
  (junction (at 209.55 101.6) (diameter 0) (color 0 0 0 0)
  )
  (junction (at 208.28 190.5) (diameter 0) (color 0 0 0 0)
  )

  (no_connect (at 193.04 132.08))
  (no_connect (at 193.04 116.84))
  (no_connect (at 193.04 114.3))
  (no_connect (at 193.04 193.04))
  (no_connect (at 193.04 139.7))
  (no_connect (at 193.04 134.62))
  (no_connect (at 193.04 142.24))
  (no_connect (at 193.04 187.96))
  (no_connect (at 193.04 144.78))
  (no_connect (at 193.04 111.76))
  (no_connect (at 193.04 137.16))
  (no_connect (at 193.04 185.42))
  (no_connect (at 193.04 147.32))
  (no_connect (at 193.04 149.86))
  (no_connect (at 193.04 119.38))
  (no_connect (at 193.04 195.58))
  (no_connect (at 210.82 152.4))
  (no_connect (at 210.82 160.02))

  (wire (pts (xy 193.04 195.58) (xy 210.82 195.58))
    (stroke (width 0) (type default))
  )
  (wire (pts (xy 193.04 223.52) (xy 210.82 223.52))
    (stroke (width 0) (type default))
  )
  (wire (pts (xy 344.17 238.76) (xy 345.44 238.76))
    (stroke (width 0) (type default))
  )
  (wire (pts (xy 208.28 231.14) (xy 208.28 233.68))
    (stroke (width 0) (type default))
  )
  (wire (pts (xy 193.04 200.66) (xy 210.82 200.66))
    (stroke (width 0) (type default))
  )
  (wire (pts (xy 193.04 144.78) (xy 210.82 144.78))
    (stroke (width 0) (type default))
  )
  (wire (pts (xy 208.28 182.88) (xy 210.82 182.88))
    (stroke (width 0) (type default))
  )
  (wire (pts (xy 208.28 198.12) (xy 208.28 190.5))
    (stroke (width 0) (type default))
  )
  (wire (pts (xy 193.04 124.46) (xy 210.82 124.46))
    (stroke (width 0) (type default))
  )
  (wire (pts (xy 193.04 132.08) (xy 210.82 132.08))
    (stroke (width 0) (type default))
  )
  (wire (pts (xy 178.435 101.6) (xy 186.69 101.6))
    (stroke (width 0) (type default))
  )
  (wire (pts (xy 193.04 226.06) (xy 210.82 226.06))
    (stroke (width 0) (type default))
  )
  (wire (pts (xy 193.04 213.36) (xy 210.82 213.36))
    (stroke (width 0) (type default))
  )
  (wire (pts (xy 193.04 218.44) (xy 210.82 218.44))
    (stroke (width 0) (type default))
  )
  (wire (pts (xy 193.04 220.98) (xy 210.82 220.98))
    (stroke (width 0) (type default))
  )
  (wire (pts (xy 193.04 177.8) (xy 210.82 177.8))
    (stroke (width 0) (type default))
  )
  (wire (pts (xy 186.69 101.6) (xy 209.55 101.6))
    (stroke (width 0) (type default))
  )
  (wire (pts (xy 193.04 154.94) (xy 210.82 154.94))
    (stroke (width 0) (type default))
  )
  (wire (pts (xy 193.04 165.1) (xy 210.82 165.1))
    (stroke (width 0) (type default))
  )
  (wire (pts (xy 210.82 106.68) (xy 209.55 106.68))
    (stroke (width 0) (type default))
  )
  (wire (pts (xy 193.04 215.9) (xy 210.82 215.9))
    (stroke (width 0) (type default))
  )
  (wire (pts (xy 208.28 190.5) (xy 210.82 190.5))
    (stroke (width 0) (type default))
  )
  (wire (pts (xy 208.28 228.6) (xy 208.28 231.14))
    (stroke (width 0) (type default))
  )
  (wire (pts (xy 193.04 127) (xy 210.82 127))
    (stroke (width 0) (type default))
  )
  (wire (pts (xy 193.04 137.16) (xy 210.82 137.16))
    (stroke (width 0) (type default))
  )
  (wire (pts (xy 193.04 187.96) (xy 210.82 187.96))
    (stroke (width 0) (type default))
  )
  (wire (pts (xy 193.04 185.42) (xy 210.82 185.42))
    (stroke (width 0) (type default))
  )
  (wire (pts (xy 193.04 172.72) (xy 210.82 172.72))
    (stroke (width 0) (type default))
  )
  (wire (pts (xy 193.04 147.32) (xy 210.82 147.32))
    (stroke (width 0) (type default))
  )
  (wire (pts (xy 193.04 157.48) (xy 210.82 157.48))
    (stroke (width 0) (type default))
  )
  (wire (pts (xy 178.435 106.045) (xy 178.435 106.68))
    (stroke (width 0) (type default))
  )
  (wire (pts (xy 193.04 121.92) (xy 210.82 121.92))
    (stroke (width 0) (type default))
  )
  (wire (pts (xy 344.17 226.06) (xy 345.44 226.06))
    (stroke (width 0) (type default))
  )
  (wire (pts (xy 193.04 111.76) (xy 210.82 111.76))
    (stroke (width 0) (type default))
  )
  (wire (pts (xy 193.04 208.28) (xy 210.82 208.28))
    (stroke (width 0) (type default))
  )
  (wire (pts (xy 193.04 162.56) (xy 210.82 162.56))
    (stroke (width 0) (type default))
  )
  (wire (pts (xy 193.04 142.24) (xy 210.82 142.24))
    (stroke (width 0) (type default))
  )
  (wire (pts (xy 178.435 106.68) (xy 186.69 106.68))
    (stroke (width 0) (type default))
  )
  (wire (pts (xy 178.435 100.965) (xy 178.435 101.6))
    (stroke (width 0) (type default))
  )
  (wire (pts (xy 186.69 100.965) (xy 186.69 101.6))
    (stroke (width 0) (type default))
  )
  (wire (pts (xy 344.17 227.33) (xy 344.17 226.06))
    (stroke (width 0) (type default))
  )
  (wire (pts (xy 193.04 114.3) (xy 210.82 114.3))
    (stroke (width 0) (type default))
  )
  (wire (pts (xy 208.28 231.14) (xy 210.82 231.14))
    (stroke (width 0) (type default))
  )
  (wire (pts (xy 208.28 190.5) (xy 208.28 182.88))
    (stroke (width 0) (type default))
  )
  (wire (pts (xy 186.69 106.68) (xy 209.55 106.68))
    (stroke (width 0) (type default))
  )
  (wire (pts (xy 193.04 139.7) (xy 210.82 139.7))
    (stroke (width 0) (type default))
  )
  (wire (pts (xy 372.11 226.06) (xy 373.38 226.06))
    (stroke (width 0) (type default))
  )
  (wire (pts (xy 372.11 238.76) (xy 373.38 238.76))
    (stroke (width 0) (type default))
  )
  (wire (pts (xy 193.04 170.18) (xy 210.82 170.18))
    (stroke (width 0) (type default))
  )
  (wire (pts (xy 344.17 240.03) (xy 344.17 238.76))
    (stroke (width 0) (type default))
  )
  (wire (pts (xy 208.28 205.74) (xy 208.28 198.12))
    (stroke (width 0) (type default))
  )
  (wire (pts (xy 372.11 227.33) (xy 372.11 226.06))
    (stroke (width 0) (type default))
  )
  (wire (pts (xy 193.04 129.54) (xy 210.82 129.54))
    (stroke (width 0) (type default))
  )
  (wire (pts (xy 208.28 198.12) (xy 210.82 198.12))
    (stroke (width 0) (type default))
  )
  (wire (pts (xy 210.82 104.14) (xy 209.55 104.14))
    (stroke (width 0) (type default))
  )
  (wire (pts (xy 193.04 203.2) (xy 210.82 203.2))
    (stroke (width 0) (type default))
  )
  (wire (pts (xy 193.04 180.34) (xy 210.82 180.34))
    (stroke (width 0) (type default))
  )
  (wire (pts (xy 208.28 228.6) (xy 210.82 228.6))
    (stroke (width 0) (type default))
  )
  (wire (pts (xy 372.11 240.03) (xy 372.11 238.76))
    (stroke (width 0) (type default))
  )
  (wire (pts (xy 209.55 104.14) (xy 209.55 101.6))
    (stroke (width 0) (type default))
  )
  (wire (pts (xy 193.04 193.04) (xy 210.82 193.04))
    (stroke (width 0) (type default))
  )
  (wire (pts (xy 209.55 106.68) (xy 209.55 109.22))
    (stroke (width 0) (type default))
  )
  (wire (pts (xy 193.04 119.38) (xy 210.82 119.38))
    (stroke (width 0) (type default))
  )
  (wire (pts (xy 209.55 101.6) (xy 210.82 101.6))
    (stroke (width 0) (type default))
  )
  (wire (pts (xy 193.04 175.26) (xy 210.82 175.26))
    (stroke (width 0) (type default))
  )
  (wire (pts (xy 210.82 205.74) (xy 208.28 205.74))
    (stroke (width 0) (type default))
  )
  (wire (pts (xy 193.04 116.84) (xy 210.82 116.84))
    (stroke (width 0) (type default))
  )
  (wire (pts (xy 186.69 106.045) (xy 186.69 106.68))
    (stroke (width 0) (type default))
  )
  (wire (pts (xy 193.04 210.82) (xy 210.82 210.82))
    (stroke (width 0) (type default))
  )
  (wire (pts (xy 209.55 109.22) (xy 210.82 109.22))
    (stroke (width 0) (type default))
  )
  (wire (pts (xy 208.28 228.6) (xy 208.28 205.74))
    (stroke (width 0) (type default))
  )
  (wire (pts (xy 193.04 134.62) (xy 210.82 134.62))
    (stroke (width 0) (type default))
  )
  (wire (pts (xy 193.04 149.86) (xy 210.82 149.86))
    (stroke (width 0) (type default))
  )
  (wire (pts (xy 193.04 167.64) (xy 210.82 167.64))
    (stroke (width 0) (type default))
  )

  (text "Camera board connector" (at 186.055 80.01 0)
    (effects (font (size 2.286 2.286)) (justify left bottom))
  )

  (label "GPIO1" (at 193.04 149.86 0) (fields_autoplaced)
    (effects (font (size 1.27 1.27)) (justify left bottom))
  )
  (label "UART3_RX" (at 193.04 137.16 0) (fields_autoplaced)
    (effects (font (size 1.27 1.27)) (justify left bottom))
  )
  (label "UART3_TX" (at 193.04 139.7 0) (fields_autoplaced)
    (effects (font (size 1.27 1.27)) (justify left bottom))
  )
  (label "CSI2_D1_P" (at 193.04 185.42 0) (fields_autoplaced)
    (effects (font (size 1.27 1.27)) (justify left bottom))
  )
  (label "UART4_RX" (at 193.04 132.08 0) (fields_autoplaced)
    (effects (font (size 1.27 1.27)) (justify left bottom))
  )
  (label "SPI_MISO" (at 193.04 116.84 0) (fields_autoplaced)
    (effects (font (size 1.27 1.27)) (justify left bottom))
  )
  (label "GPIO2" (at 193.04 147.32 0) (fields_autoplaced)
    (effects (font (size 1.27 1.27)) (justify left bottom))
  )
  (label "UART4_TX" (at 193.04 134.62 0) (fields_autoplaced)
    (effects (font (size 1.27 1.27)) (justify left bottom))
  )
  (label "SPI_MOSI" (at 193.04 114.3 0) (fields_autoplaced)
    (effects (font (size 1.27 1.27)) (justify left bottom))
  )
  (label "CSI2_CLK_P" (at 193.04 193.04 0) (fields_autoplaced)
    (effects (font (size 1.27 1.27)) (justify left bottom))
  )
  (label "GPIO3" (at 193.04 144.78 0) (fields_autoplaced)
    (effects (font (size 1.27 1.27)) (justify left bottom))
  )
  (label "SPI_SCK" (at 193.04 119.38 0) (fields_autoplaced)
    (effects (font (size 1.27 1.27)) (justify left bottom))
  )
  (label "CSI2_CLK_N" (at 193.04 195.58 0) (fields_autoplaced)
    (effects (font (size 1.27 1.27)) (justify left bottom))
  )
  (label "GPIO4" (at 193.04 142.24 0) (fields_autoplaced)
    (effects (font (size 1.27 1.27)) (justify left bottom))
  )
  (label "SPI_CS" (at 193.04 111.76 0) (fields_autoplaced)
    (effects (font (size 1.27 1.27)) (justify left bottom))
  )
  (label "CSI2_D1_N" (at 193.04 187.96 0) (fields_autoplaced)
    (effects (font (size 1.27 1.27)) (justify left bottom))
  )

  (global_label "CSI1_CLK_N" (shape input) (at 193.04 157.48 180) (fields_autoplaced)
    (effects (font (size 1.27 1.27)) (justify right))
    (property "Intersheetrefs" "${INTERSHEET_REFS}" (at 179.4993 157.5594 0)
      (effects (font (size 1.27 1.27)) (justify right) hide)
    )
  )
  (global_label "I2C1_SCL" (shape input) (at 193.04 121.92 180) (fields_autoplaced)
    (effects (font (size 1.27 1.27)) (justify right))
    (property "Intersheetrefs" "${INTERSHEET_REFS}" (at 181.8579 121.9994 0)
      (effects (font (size 1.27 1.27)) (justify right) hide)
    )
  )
  (global_label "CSI3_D1_N" (shape input) (at 193.04 210.82 180) (fields_autoplaced)
    (effects (font (size 1.27 1.27)) (justify right))
    (property "Intersheetrefs" "${INTERSHEET_REFS}" (at 180.5879 210.8994 0)
      (effects (font (size 1.27 1.27)) (justify right) hide)
    )
  )
  (global_label "CSI3_D3_P" (shape input) (at 193.04 218.44 180) (fields_autoplaced)
    (effects (font (size 1.27 1.27)) (justify right))
    (property "Intersheetrefs" "${INTERSHEET_REFS}" (at 180.6483 218.5194 0)
      (effects (font (size 1.27 1.27)) (justify right) hide)
    )
  )
  (global_label "CSI1_D4_N" (shape input) (at 193.04 180.34 180) (fields_autoplaced)
    (effects (font (size 1.27 1.27)) (justify right))
    (property "Intersheetrefs" "${INTERSHEET_REFS}" (at 180.5879 180.4194 0)
      (effects (font (size 1.27 1.27)) (justify right) hide)
    )
  )
  (global_label "CSI3_D4_N" (shape input) (at 193.04 226.06 180) (fields_autoplaced)
    (effects (font (size 1.27 1.27)) (justify right))
    (property "Intersheetrefs" "${INTERSHEET_REFS}" (at 180.5879 226.1394 0)
      (effects (font (size 1.27 1.27)) (justify right) hide)
    )
  )
  (global_label "CSI1_D3_N" (shape input) (at 193.04 175.26 180) (fields_autoplaced)
    (effects (font (size 1.27 1.27)) (justify right))
    (property "Intersheetrefs" "${INTERSHEET_REFS}" (at 180.5879 175.3394 0)
      (effects (font (size 1.27 1.27)) (justify right) hide)
    )
  )
  (global_label "CSI1_D1_P" (shape input) (at 193.04 162.56 180) (fields_autoplaced)
    (effects (font (size 1.27 1.27)) (justify right))
    (property "Intersheetrefs" "${INTERSHEET_REFS}" (at 180.6483 162.6394 0)
      (effects (font (size 1.27 1.27)) (justify right) hide)
    )
  )
  (global_label "CSI3_D1_P" (shape input) (at 193.04 208.28 180) (fields_autoplaced)
    (effects (font (size 1.27 1.27)) (justify right))
    (property "Intersheetrefs" "${INTERSHEET_REFS}" (at 180.6483 208.3594 0)
      (effects (font (size 1.27 1.27)) (justify right) hide)
    )
  )
  (global_label "CSI1_D4_P" (shape input) (at 193.04 177.8 180) (fields_autoplaced)
    (effects (font (size 1.27 1.27)) (justify right))
    (property "Intersheetrefs" "${INTERSHEET_REFS}" (at 180.6483 177.8794 0)
      (effects (font (size 1.27 1.27)) (justify right) hide)
    )
  )
  (global_label "CSI3_CLK_N" (shape input) (at 193.04 203.2 180) (fields_autoplaced)
    (effects (font (size 1.27 1.27)) (justify right))
    (property "Intersheetrefs" "${INTERSHEET_REFS}" (at 179.4993 203.2794 0)
      (effects (font (size 1.27 1.27)) (justify right) hide)
    )
  )
  (global_label "I2C3_SDA" (shape input) (at 193.04 129.54 180) (fields_autoplaced)
    (effects (font (size 1.27 1.27)) (justify right))
    (property "Intersheetrefs" "${INTERSHEET_REFS}" (at 181.7974 129.6194 0)
      (effects (font (size 1.27 1.27)) (justify right) hide)
    )
  )
  (global_label "CSI1_CLK_P" (shape input) (at 193.04 154.94 180) (fields_autoplaced)
    (effects (font (size 1.27 1.27)) (justify right))
    (property "Intersheetrefs" "${INTERSHEET_REFS}" (at 179.5598 155.0194 0)
      (effects (font (size 1.27 1.27)) (justify right) hide)
    )
  )
  (global_label "CSI3_D2_P" (shape input) (at 193.04 213.36 180) (fields_autoplaced)
    (effects (font (size 1.27 1.27)) (justify right))
    (property "Intersheetrefs" "${INTERSHEET_REFS}" (at 180.6483 213.4394 0)
      (effects (font (size 1.27 1.27)) (justify right) hide)
    )
  )
  (global_label "I2C3_SCL" (shape input) (at 193.04 127 180) (fields_autoplaced)
    (effects (font (size 1.27 1.27)) (justify right))
    (property "Intersheetrefs" "${INTERSHEET_REFS}" (at 181.8579 127.0794 0)
      (effects (font (size 1.27 1.27)) (justify right) hide)
    )
  )
  (global_label "CSI3_D2_N" (shape input) (at 193.04 215.9 180) (fields_autoplaced)
    (effects (font (size 1.27 1.27)) (justify right))
    (property "Intersheetrefs" "${INTERSHEET_REFS}" (at 180.5879 215.9794 0)
      (effects (font (size 1.27 1.27)) (justify right) hide)
    )
  )
  (global_label "CSI1_D2_N" (shape input) (at 193.04 170.18 180) (fields_autoplaced)
    (effects (font (size 1.27 1.27)) (justify right))
    (property "Intersheetrefs" "${INTERSHEET_REFS}" (at 180.5879 170.2594 0)
      (effects (font (size 1.27 1.27)) (justify right) hide)
    )
  )
  (global_label "CSI1_D2_P" (shape input) (at 193.04 167.64 180) (fields_autoplaced)
    (effects (font (size 1.27 1.27)) (justify right))
    (property "Intersheetrefs" "${INTERSHEET_REFS}" (at 180.6483 167.7194 0)
      (effects (font (size 1.27 1.27)) (justify right) hide)
    )
  )
  (global_label "CSI3_CLK_P" (shape input) (at 193.04 200.66 180) (fields_autoplaced)
    (effects (font (size 1.27 1.27)) (justify right))
    (property "Intersheetrefs" "${INTERSHEET_REFS}" (at 179.5598 200.7394 0)
      (effects (font (size 1.27 1.27)) (justify right) hide)
    )
  )
  (global_label "CSI3_D4_P" (shape input) (at 193.04 223.52 180) (fields_autoplaced)
    (effects (font (size 1.27 1.27)) (justify right))
    (property "Intersheetrefs" "${INTERSHEET_REFS}" (at 180.6483 223.5994 0)
      (effects (font (size 1.27 1.27)) (justify right) hide)
    )
  )
  (global_label "CSI1_D3_P" (shape input) (at 193.04 172.72 180) (fields_autoplaced)
    (effects (font (size 1.27 1.27)) (justify right))
    (property "Intersheetrefs" "${INTERSHEET_REFS}" (at 180.6483 172.7994 0)
      (effects (font (size 1.27 1.27)) (justify right) hide)
    )
  )
  (global_label "CSI3_D3_N" (shape input) (at 193.04 220.98 180) (fields_autoplaced)
    (effects (font (size 1.27 1.27)) (justify right))
    (property "Intersheetrefs" "${INTERSHEET_REFS}" (at 180.5879 221.0594 0)
      (effects (font (size 1.27 1.27)) (justify right) hide)
    )
  )
  (global_label "I2C1_SDA" (shape input) (at 193.04 124.46 180) (fields_autoplaced)
    (effects (font (size 1.27 1.27)) (justify right))
    (property "Intersheetrefs" "${INTERSHEET_REFS}" (at 181.7974 124.5394 0)
      (effects (font (size 1.27 1.27)) (justify right) hide)
    )
  )
  (global_label "CSI1_D1_N" (shape input) (at 193.04 165.1 180) (fields_autoplaced)
    (effects (font (size 1.27 1.27)) (justify right))
    (property "Intersheetrefs" "${INTERSHEET_REFS}" (at 180.5879 165.1794 0)
      (effects (font (size 1.27 1.27)) (justify right) hide)
    )
  )

  (symbol (lib_id "antmicropower:PWR_FLAG") (at 186.69 106.045 0) (mirror y) (unit 1)
    (in_bom yes) (on_board yes) (dnp no)
    (property "Reference" "#FLG0111" (at 186.69 104.14 0)
      (effects (font (size 1.27 1.27)) hide)
    )
    (property "Value" "PWR_FLAG" (at 197.485 104.775 0)
      (effects (font (size 1.27 1.27)) (justify left))
    )
    (property "Footprint" "" (at 186.69 106.045 0)
      (effects (font (size 1.27 1.27)) hide)
    )
    (property "Datasheet" "" (at 186.69 106.045 0)
      (effects (font (size 1.27 1.27)) hide)
    )
    (pin "1")
    (instances
      (project "antmicro-hdmi-mipi-bridge-hw"
        (path ""
          (reference "#FLG0111") (unit 1)
        )
      )
    )
  )

  (symbol (lib_id "antmicroMechanicalParts:Spacer_Drill3.7mm_H6mm_9774060151R") (at 373.38 238.76 0) (unit 1)
    (in_bom yes) (on_board yes) (dnp no)
    (property "Reference" "SP4" (at 376.555 232.41 0)
      (effects (font (size 1.524 1.524)) (justify left))
    )
    (property "Value" "Spacer_Drill3.7mm_H6mm_9774060151R" (at 396.24 243.84 0)
      (effects (font (size 1.27 1.27) (thickness 0.15)) (justify left bottom) hide)
    )
    (property "Footprint" "antmicro-footprints:Spacer_Drill3.7mm_H6mm_9774060151R" (at 396.24 246.38 0)
      (effects (font (size 1.27 1.27) (thickness 0.15)) (justify left bottom) hide)
    )
    (property "Datasheet" "https://www.we-online.com/components/products/datasheet/9774060151R.pdf" (at 396.24 248.92 0)
      (effects (font (size 1.27 1.27) (thickness 0.15)) (justify left bottom) hide)
    )
    (property "Manufacturer" "Würth Elektronik" (at 396.24 251.46 0)
      (effects (font (size 1.27 1.27) (thickness 0.15)) (justify left bottom) hide)
    )
    (property "MPN" "9774060151R" (at 372.11 235.585 0)
      (effects (font (size 1.27 1.27) (thickness 0.15)) (justify left bottom))
    )
    (property "Author" "Antmicro" (at 396.24 256.54 0)
      (effects (font (size 1.27 1.27) (thickness 0.15)) (justify left bottom) hide)
    )
    (property "License" "Apache-2.0" (at 396.24 259.08 0)
      (effects (font (size 1.27 1.27) (thickness 0.15)) (justify left bottom) hide)
    )
    (property "Public" "False" (at 396.24 251.46 0)
      (effects (font (size 1.27 1.27)) (justify left bottom) hide)
    )
    (pin "1")
    (instances
      (project "antmicro-hdmi-mipi-bridge-hw"
        (path ""
          (reference "SP4") (unit 1)
        )
      )
    )
  )

  (symbol (lib_id "antmicropower:GND") (at 344.17 240.03 0) (unit 1)
    (in_bom yes) (on_board yes) (dnp no)
    (property "Reference" "#PWR0192" (at 344.17 246.38 0)
      (effects (font (size 1.27 1.27)) hide)
    )
    (property "Value" "GND" (at 342.265 244.475 0)
      (effects (font (size 1.27 1.27) (thickness 0.15)) (justify left bottom))
    )
    (property "Footprint" "" (at 344.17 240.03 0)
      (effects (font (size 1.27 1.27) (thickness 0.15)) (justify left bottom) hide)
    )
    (property "Datasheet" "" (at 344.17 240.03 0)
      (effects (font (size 1.27 1.27) (thickness 0.15)) (justify left bottom) hide)
    )
    (property "Author" "Antmicro" (at 353.06 247.65 0)
      (effects (font (size 1.27 1.27) (thickness 0.15)) (justify left bottom) hide)
    )
    (property "License" "Apache-2.0" (at 353.06 250.19 0)
      (effects (font (size 1.27 1.27) (thickness 0.15)) (justify left bottom) hide)
    )
    (pin "1")
    (instances
      (project "antmicro-hdmi-mipi-bridge-hw"
        (path ""
          (reference "#PWR0192") (unit 1)
        )
      )
    )
  )

  (symbol (lib_id "antmicroMechanicalParts:Spacer_Drill3.7mm_H6mm_9774060151R") (at 345.44 226.06 0) (unit 1)
    (in_bom yes) (on_board yes) (dnp no)
    (property "Reference" "SP1" (at 347.98 219.71 0)
      (effects (font (size 1.524 1.524)) (justify left))
    )
    (property "Value" "Spacer_Drill3.7mm_H6mm_9774060151R" (at 368.3 231.14 0)
      (effects (font (size 1.27 1.27) (thickness 0.15)) (justify left bottom) hide)
    )
    (property "Footprint" "antmicro-footprints:Spacer_Drill3.7mm_H6mm_9774060151R" (at 368.3 233.68 0)
      (effects (font (size 1.27 1.27) (thickness 0.15)) (justify left bottom) hide)
    )
    (property "Datasheet" "https://www.we-online.com/components/products/datasheet/9774060151R.pdf" (at 368.3 236.22 0)
      (effects (font (size 1.27 1.27) (thickness 0.15)) (justify left bottom) hide)
    )
    (property "Manufacturer" "Würth Elektronik" (at 368.3 238.76 0)
      (effects (font (size 1.27 1.27) (thickness 0.15)) (justify left bottom) hide)
    )
    (property "MPN" "9774060151R" (at 344.17 222.885 0)
      (effects (font (size 1.27 1.27) (thickness 0.15)) (justify left bottom))
    )
    (property "Author" "Antmicro" (at 368.3 243.84 0)
      (effects (font (size 1.27 1.27) (thickness 0.15)) (justify left bottom) hide)
    )
    (property "License" "Apache-2.0" (at 368.3 246.38 0)
      (effects (font (size 1.27 1.27) (thickness 0.15)) (justify left bottom) hide)
    )
    (property "Public" "False" (at 368.3 238.76 0)
      (effects (font (size 1.27 1.27)) (justify left bottom) hide)
    )
    (pin "1")
    (instances
      (project "antmicro-hdmi-mipi-bridge-hw"
        (path ""
          (reference "SP1") (unit 1)
        )
      )
    )
  )

  (symbol (lib_id "antmicroMechanicalParts:Spacer_Drill3.7mm_H6mm_9774060151R") (at 373.38 226.06 0) (unit 1)
    (in_bom yes) (on_board yes) (dnp no)
    (property "Reference" "SP3" (at 376.555 219.71 0)
      (effects (font (size 1.524 1.524)) (justify left))
    )
    (property "Value" "Spacer_Drill3.7mm_H6mm_9774060151R" (at 396.24 231.14 0)
      (effects (font (size 1.27 1.27) (thickness 0.15)) (justify left bottom) hide)
    )
    (property "Footprint" "antmicro-footprints:Spacer_Drill3.7mm_H6mm_9774060151R" (at 396.24 233.68 0)
      (effects (font (size 1.27 1.27) (thickness 0.15)) (justify left bottom) hide)
    )
    (property "Datasheet" "https://www.we-online.com/components/products/datasheet/9774060151R.pdf" (at 396.24 236.22 0)
      (effects (font (size 1.27 1.27) (thickness 0.15)) (justify left bottom) hide)
    )
    (property "Manufacturer" "Würth Elektronik" (at 396.24 238.76 0)
      (effects (font (size 1.27 1.27) (thickness 0.15)) (justify left bottom) hide)
    )
    (property "MPN" "9774060151R" (at 372.11 222.885 0)
      (effects (font (size 1.27 1.27) (thickness 0.15)) (justify left bottom))
    )
    (property "Author" "Antmicro" (at 396.24 243.84 0)
      (effects (font (size 1.27 1.27) (thickness 0.15)) (justify left bottom) hide)
    )
    (property "License" "Apache-2.0" (at 396.24 246.38 0)
      (effects (font (size 1.27 1.27) (thickness 0.15)) (justify left bottom) hide)
    )
    (property "Public" "False" (at 396.24 238.76 0)
      (effects (font (size 1.27 1.27)) (justify left bottom) hide)
    )
    (pin "1")
    (instances
      (project "antmicro-hdmi-mipi-bridge-hw"
        (path ""
          (reference "SP3") (unit 1)
        )
      )
    )
  )

  (symbol (lib_id "antmicropower:PWR_FLAG") (at 186.69 100.965 0) (mirror y) (unit 1)
    (in_bom yes) (on_board yes) (dnp no)
    (property "Reference" "#FLG0110" (at 186.69 99.06 0)
      (effects (font (size 1.27 1.27)) hide)
    )
    (property "Value" "PWR_FLAG" (at 197.485 99.695 0)
      (effects (font (size 1.27 1.27)) (justify left))
    )
    (property "Footprint" "" (at 186.69 100.965 0)
      (effects (font (size 1.27 1.27)) hide)
    )
    (property "Datasheet" "" (at 186.69 100.965 0)
      (effects (font (size 1.27 1.27)) hide)
    )
    (pin "1")
    (instances
      (project "antmicro-hdmi-mipi-bridge-hw"
        (path ""
          (reference "#FLG0110") (unit 1)
        )
      )
    )
  )

  (symbol (lib_id "antmicroMechanicalParts:Spacer_Drill3.7mm_H6mm_9774060151R") (at 345.44 238.76 0) (unit 1)
    (in_bom yes) (on_board yes) (dnp no)
    (property "Reference" "SP2" (at 347.98 232.41 0)
      (effects (font (size 1.524 1.524)) (justify left))
    )
    (property "Value" "Spacer_Drill3.7mm_H6mm_9774060151R" (at 368.3 243.84 0)
      (effects (font (size 1.27 1.27) (thickness 0.15)) (justify left bottom) hide)
    )
    (property "Footprint" "antmicro-footprints:Spacer_Drill3.7mm_H6mm_9774060151R" (at 368.3 246.38 0)
      (effects (font (size 1.27 1.27) (thickness 0.15)) (justify left bottom) hide)
    )
    (property "Datasheet" "https://www.we-online.com/components/products/datasheet/9774060151R.pdf" (at 368.3 248.92 0)
      (effects (font (size 1.27 1.27) (thickness 0.15)) (justify left bottom) hide)
    )
    (property "Manufacturer" "Würth Elektronik" (at 368.3 251.46 0)
      (effects (font (size 1.27 1.27) (thickness 0.15)) (justify left bottom) hide)
    )
    (property "MPN" "9774060151R" (at 344.17 235.585 0)
      (effects (font (size 1.27 1.27) (thickness 0.15)) (justify left bottom))
    )
    (property "Author" "Antmicro" (at 368.3 256.54 0)
      (effects (font (size 1.27 1.27) (thickness 0.15)) (justify left bottom) hide)
    )
    (property "License" "Apache-2.0" (at 368.3 259.08 0)
      (effects (font (size 1.27 1.27) (thickness 0.15)) (justify left bottom) hide)
    )
    (property "Public" "False" (at 368.3 251.46 0)
      (effects (font (size 1.27 1.27)) (justify left bottom) hide)
    )
    (pin "1")
    (instances
      (project "antmicro-hdmi-mipi-bridge-hw"
        (path ""
          (reference "SP2") (unit 1)
        )
      )
    )
  )

  (symbol (lib_id "antmicroFCCConnectors:Conn_FFC_WE_68715014022") (at 210.82 101.6 0) (unit 1)
    (in_bom yes) (on_board yes) (dnp no)
    (property "Reference" "J6" (at 216.535 95.25 0)
      (effects (font (size 1.27 1.27) (thickness 0.15)))
    )
    (property "Value" "Conn_FFC_WE_68715014022" (at 213.36 97.79 0)
      (effects (font (size 1.27 1.27) (thickness 0.15)) hide)
    )
    (property "Footprint" "antmicro-footprints:Conn_FFC_WE_68715014x22" (at 229.87 111.76 0)
      (effects (font (size 1.27 1.27) (thickness 0.15)) (justify left bottom) hide)
    )
    (property "Datasheet" "https://www.we-online.com/components/products/datasheet/68715014022.pdf" (at 229.87 114.3 0)
      (effects (font (size 1.27 1.27) (thickness 0.15)) (justify left bottom) hide)
    )
    (property "MPN" "68715014022" (at 209.55 98.425 0)
      (effects (font (size 1.27 1.27) (thickness 0.15)) (justify left bottom))
    )
    (property "Manufacturer" "Würth Elektronik" (at 229.87 119.38 0)
      (effects (font (size 1.27 1.27) (thickness 0.15)) (justify left bottom) hide)
    )
    (property "Author" "Antmicro" (at 229.87 121.92 0)
      (effects (font (size 1.27 1.27) (thickness 0.15)) (justify left bottom) hide)
    )
    (property "License" "Apache-2.0" (at 229.87 124.46 0)
      (effects (font (size 1.27 1.27) (thickness 0.15)) (justify left bottom) hide)
    )
    (pin "9")
    (pin "24")
    (pin "35")
    (pin "6")
    (pin "20")
    (pin "33")
    (pin "19")
    (pin "2")
    (pin "7")
    (pin "3")
    (pin "46")
    (pin "48")
    (pin "47")
    (pin "50")
    (pin "5")
    (pin "49")
    (pin "43")
    (pin "27")
    (pin "32")
    (pin "40")
    (pin "23")
    (pin "30")
    (pin "21")
    (pin "17")
    (pin "45")
    (pin "44")
    (pin "18")
    (pin "1")
    (pin "13")
    (pin "41")
    (pin "22")
    (pin "29")
    (pin "16")
    (pin "36")
    (pin "25")
    (pin "MP1")
    (pin "38")
    (pin "39")
    (pin "4")
    (pin "37")
    (pin "31")
    (pin "26")
    (pin "8")
    (pin "MP2")
    (pin "34")
    (pin "42")
    (pin "12")
    (pin "28")
    (pin "14")
    (pin "11")
    (pin "10")
    (pin "15")
    (instances
      (project "antmicro-hdmi-mipi-bridge-hw"
        (path ""
          (reference "J6") (unit 1)
        )
      )
    )
  )

  (symbol (lib_id "antmicropower:GND") (at 208.28 233.68 0) (unit 1)
    (in_bom yes) (on_board yes) (dnp no)
    (property "Reference" "#PWR0101" (at 208.28 240.03 0)
      (effects (font (size 1.27 1.27)) hide)
    )
    (property "Value" "GND" (at 206.375 238.76 0)
      (effects (font (size 1.27 1.27) (thickness 0.15)) (justify left bottom))
    )
    (property "Footprint" "" (at 208.28 233.68 0)
      (effects (font (size 1.27 1.27) (thickness 0.15)) (justify left bottom) hide)
    )
    (property "Datasheet" "" (at 208.28 233.68 0)
      (effects (font (size 1.27 1.27) (thickness 0.15)) (justify left bottom) hide)
    )
    (property "Author" "Antmicro" (at 217.17 241.3 0)
      (effects (font (size 1.27 1.27) (thickness 0.15)) (justify left bottom) hide)
    )
    (property "License" "Apache-2.0" (at 217.17 243.84 0)
      (effects (font (size 1.27 1.27) (thickness 0.15)) (justify left bottom) hide)
    )
    (pin "1")
    (instances
      (project "antmicro-hdmi-mipi-bridge-hw"
        (path ""
          (reference "#PWR0101") (unit 1)
        )
      )
    )
  )

  (symbol (lib_id "antmicropower:+3V3") (at 178.435 106.045 0) (mirror y) (unit 1)
    (in_bom yes) (on_board yes) (dnp no)
    (property "Reference" "#PWR0102" (at 178.435 109.855 0)
      (effects (font (size 1.27 1.27)) hide)
    )
    (property "Value" "+3V3" (at 177.165 104.775 0)
      (effects (font (size 1.27 1.27) (thickness 0.15)) (justify left bottom))
    )
    (property "Footprint" "" (at 178.435 106.045 0)
      (effects (font (size 1.27 1.27) (thickness 0.15)) (justify left bottom) hide)
    )
    (property "Datasheet" "" (at 178.435 106.045 0)
      (effects (font (size 1.27 1.27) (thickness 0.15)) (justify left bottom) hide)
    )
    (property "Author" "Antmicro" (at 163.195 108.585 0)
      (effects (font (size 1.27 1.27) (thickness 0.15)) (justify left bottom) hide)
    )
    (property "License" "Apache-2.0" (at 163.195 111.125 0)
      (effects (font (size 1.27 1.27) (thickness 0.15)) (justify left bottom) hide)
    )
    (pin "1")
    (instances
      (project "antmicro-hdmi-mipi-bridge-hw"
        (path ""
          (reference "#PWR0102") (unit 1)
        )
      )
    )
  )

  (symbol (lib_id "antmicropower:+5V") (at 178.435 100.965 0) (mirror y) (unit 1)
    (in_bom yes) (on_board yes) (dnp no)
    (property "Reference" "#PWR0103" (at 178.435 104.775 0)
      (effects (font (size 1.27 1.27)) hide)
    )
    (property "Value" "+5V" (at 177.165 99.695 0)
      (effects (font (size 1.27 1.27) (thickness 0.15)) (justify left bottom))
    )
    (property "Footprint" "" (at 178.435 100.965 0)
      (effects (font (size 1.27 1.27) (thickness 0.15)) (justify left bottom) hide)
    )
    (property "Datasheet" "" (at 178.435 100.965 0)
      (effects (font (size 1.27 1.27) (thickness 0.15)) (justify left bottom) hide)
    )
    (property "Author" "Antmicro" (at 163.195 108.585 0)
      (effects (font (size 1.27 1.27) (thickness 0.15)) (justify left bottom) hide)
    )
    (property "License" "Apache-2.0" (at 163.195 111.125 0)
      (effects (font (size 1.27 1.27) (thickness 0.15)) (justify left bottom) hide)
    )
    (pin "1")
    (instances
      (project "antmicro-hdmi-mipi-bridge-hw"
        (path ""
          (reference "#PWR0103") (unit 1)
        )
      )
    )
  )

  (symbol (lib_id "antmicropower:GND") (at 372.11 227.33 0) (unit 1)
    (in_bom yes) (on_board yes) (dnp no)
    (property "Reference" "#PWR0194" (at 372.11 233.68 0)
      (effects (font (size 1.27 1.27)) hide)
    )
    (property "Value" "GND" (at 370.205 231.775 0)
      (effects (font (size 1.27 1.27) (thickness 0.15)) (justify left bottom))
    )
    (property "Footprint" "" (at 372.11 227.33 0)
      (effects (font (size 1.27 1.27) (thickness 0.15)) (justify left bottom) hide)
    )
    (property "Datasheet" "" (at 372.11 227.33 0)
      (effects (font (size 1.27 1.27) (thickness 0.15)) (justify left bottom) hide)
    )
    (property "Author" "Antmicro" (at 381 234.95 0)
      (effects (font (size 1.27 1.27) (thickness 0.15)) (justify left bottom) hide)
    )
    (property "License" "Apache-2.0" (at 381 237.49 0)
      (effects (font (size 1.27 1.27) (thickness 0.15)) (justify left bottom) hide)
    )
    (pin "1")
    (instances
      (project "antmicro-hdmi-mipi-bridge-hw"
        (path ""
          (reference "#PWR0194") (unit 1)
        )
      )
    )
  )

  (symbol (lib_id "antmicropower:GND") (at 372.11 240.03 0) (unit 1)
    (in_bom yes) (on_board yes) (dnp no)
    (property "Reference" "#PWR0193" (at 372.11 246.38 0)
      (effects (font (size 1.27 1.27)) hide)
    )
    (property "Value" "GND" (at 370.205 244.475 0)
      (effects (font (size 1.27 1.27) (thickness 0.15)) (justify left bottom))
    )
    (property "Footprint" "" (at 372.11 240.03 0)
      (effects (font (size 1.27 1.27) (thickness 0.15)) (justify left bottom) hide)
    )
    (property "Datasheet" "" (at 372.11 240.03 0)
      (effects (font (size 1.27 1.27) (thickness 0.15)) (justify left bottom) hide)
    )
    (property "Author" "Antmicro" (at 381 247.65 0)
      (effects (font (size 1.27 1.27) (thickness 0.15)) (justify left bottom) hide)
    )
    (property "License" "Apache-2.0" (at 381 250.19 0)
      (effects (font (size 1.27 1.27) (thickness 0.15)) (justify left bottom) hide)
    )
    (pin "1")
    (instances
      (project "antmicro-hdmi-mipi-bridge-hw"
        (path ""
          (reference "#PWR0193") (unit 1)
        )
      )
    )
  )

  (symbol (lib_id "antmicropower:GND") (at 344.17 227.33 0) (unit 1)
    (in_bom yes) (on_board yes) (dnp no)
    (property "Reference" "#PWR0195" (at 344.17 233.68 0)
      (effects (font (size 1.27 1.27)) hide)
    )
    (property "Value" "GND" (at 342.265 231.775 0)
      (effects (font (size 1.27 1.27) (thickness 0.15)) (justify left bottom))
    )
    (property "Footprint" "" (at 344.17 227.33 0)
      (effects (font (size 1.27 1.27) (thickness 0.15)) (justify left bottom) hide)
    )
    (property "Datasheet" "" (at 344.17 227.33 0)
      (effects (font (size 1.27 1.27) (thickness 0.15)) (justify left bottom) hide)
    )
    (property "Author" "Antmicro" (at 353.06 234.95 0)
      (effects (font (size 1.27 1.27) (thickness 0.15)) (justify left bottom) hide)
    )
    (property "License" "Apache-2.0" (at 353.06 237.49 0)
      (effects (font (size 1.27 1.27) (thickness 0.15)) (justify left bottom) hide)
    )
    (pin "1")
    (instances
      (project "antmicro-hdmi-mipi-bridge-hw"
        (path ""
          (reference "#PWR0195") (unit 1)
        )
      )
    )
  )
)
